(kicad_pcb
	(version 20260206)
	(generator "pcbnew")
	(generator_version "10.0")
	(general
		(thickness 1.6)
		(legacy_teardrops no)
	)
	(paper "A4")
	(title_block
		(title "01162023_DA0F0TEBIF0_F0T_Expander_BD_F_brd_V02_OCP.brd")
		(comment 1 "Grand Teton / footprints 8864-8870 of 9728")
	)
	(layers
		(0 "F.Cu" signal "TOP")
		(4 "In1.Cu" signal "GND")
		(6 "In2.Cu" signal "VCC")
		(8 "In3.Cu" signal "VCC1")
		(10 "In4.Cu" signal "GND1")
		(12 "In5.Cu" signal "IN1")
		(14 "In6.Cu" signal "GND2")
		(16 "In7.Cu" signal "IN2")
		(18 "In8.Cu" signal "GND3")
		(20 "In9.Cu" signal "IN3")
		(22 "In10.Cu" signal "GND4")
		(24 "In11.Cu" signal "IN4")
		(26 "In12.Cu" signal "GND5")
		(28 "In13.Cu" signal "IN5")
		(30 "In14.Cu" signal "GND6")
		(32 "In15.Cu" signal "IN6")
		(34 "In16.Cu" signal "GND7")
		(2 "B.Cu" signal "BOTTOM")
		(9 "F.Adhes" user "F.Adhesive")
		(11 "B.Adhes" user "B.Adhesive")
		(13 "F.Paste" user "Package Geometry/Pastemask Top")
		(15 "B.Paste" user "Package Geometry/Pastemask Bottom")
		(5 "F.SilkS" user "Ref Des/Silkscreen Top")
		(7 "B.SilkS" user "Ref Des/Silkscreen Bottom")
		(1 "F.Mask" user "Board Geometry/Soldermask Top")
		(3 "B.Mask" user "Board Geometry/Soldermask Bottom")
		(17 "Dwgs.User" user "User.Drawings")
		(19 "Cmts.User" user "User.Comments")
		(21 "Eco1.User" user "User.Eco1")
		(23 "Eco2.User" user "User.Eco2")
		(25 "Edge.Cuts" user "Board Geometry/Outline")
		(27 "Margin" user)
		(31 "F.CrtYd" user "Package Geometry/Place Bound Top")
		(29 "B.CrtYd" user "Package Geometry/Place Bound Bottom")
		(35 "F.Fab" user "Ref Des/Assembly Top")
		(33 "B.Fab" user "Ref Des/Assembly Bottom")
	)
	(footprint ""
		(layer "B.Cu")
		(at 247.099582 -228.981)
		(property "Reference" "R3485"
			(at 0 0 0)
			(layer "B.SilkS")
			(hide yes)
			(effects
				(font
					(size 1.27 1.27)
				)
				(justify mirror)
			)
		)
		(property "Value" ""
			(at 0 0 0)
			(layer "B.Fab")
			(effects
				(font
					(size 1.27 1.27)
				)
				(justify mirror)
			)
		)
		(duplicate_pad_numbers_are_jumpers no)
		(fp_line
			(start -0.7874 -0.4064)
			(end -0.7874 0.4064)
			(stroke
				(width 0.1524)
				(type default)
			)
			(layer "B.SilkS")
		)
		(fp_line
			(start -0.7874 0.4064)
			(end 0.7874 0.4064)
			(stroke
				(width 0.1524)
				(type default)
			)
			(layer "B.SilkS")
		)
		(fp_line
			(start 0.7874 -0.4064)
			(end -0.7874 -0.4064)
			(stroke
				(width 0.1524)
				(type default)
			)
			(layer "B.SilkS")
		)
		(fp_line
			(start 0.7874 0.4064)
			(end 0.7874 -0.4064)
			(stroke
				(width 0.1524)
				(type default)
			)
			(layer "B.SilkS")
		)
		(fp_line
			(start -0.67945 -0.3048)
			(end -0.67945 0.3048)
			(stroke
				(width 0.1)
				(type default)
			)
			(layer "B.Fab")
		)
		(fp_line
			(start -0.67945 0.3048)
			(end -0.120396 0.3048)
			(stroke
				(width 0.1)
				(type default)
			)
			(layer "B.Fab")
		)
		(fp_line
			(start -0.12065 -0.3048)
			(end -0.67945 -0.3048)
			(stroke
				(width 0.1)
				(type default)
			)
			(layer "B.Fab")
		)
		(fp_line
			(start -0.12065 -0.2794)
			(end -0.12065 -0.3048)
			(stroke
				(width 0.1)
				(type default)
			)
			(layer "B.Fab")
		)
		(fp_line
			(start -0.120396 0.2794)
			(end 0.12065 0.2794)
			(stroke
				(width 0.1)
				(type default)
			)
			(layer "B.Fab")
		)
		(fp_line
			(start -0.120396 0.3048)
			(end -0.120396 0.2794)
			(stroke
				(width 0.1)
				(type default)
			)
			(layer "B.Fab")
		)
		(fp_line
			(start 0.12065 -0.305054)
			(end 0.12065 -0.2794)
			(stroke
				(width 0.1)
				(type default)
			)
			(layer "B.Fab")
		)
		(fp_line
			(start 0.12065 -0.2794)
			(end -0.12065 -0.2794)
			(stroke
				(width 0.1)
				(type default)
			)
			(layer "B.Fab")
		)
		(fp_line
			(start 0.12065 0.2794)
			(end 0.12065 0.3048)
			(stroke
				(width 0.1)
				(type default)
			)
			(layer "B.Fab")
		)
		(fp_line
			(start 0.12065 0.3048)
			(end 0.67945 0.3048)
			(stroke
				(width 0.1)
				(type default)
			)
			(layer "B.Fab")
		)
		(fp_line
			(start 0.67945 -0.305054)
			(end 0.12065 -0.305054)
			(stroke
				(width 0.1)
				(type default)
			)
			(layer "B.Fab")
		)
		(fp_line
			(start 0.67945 0.3048)
			(end 0.67945 -0.305054)
			(stroke
				(width 0.1)
				(type default)
			)
			(layer "B.Fab")
		)
		(pad "1" smd circle
			(at 0.40005 0 180)
			(size 0 0)
			(layers "B.Cu" "B.Mask" "B.Paste")
			(net "P1V8_PEX")
		)
		(pad "2" smd circle
			(at -0.40005 0 180)
			(size 0 0)
			(layers "B.Cu" "B.Mask" "B.Paste")
			(net "SPI_PEX2_SDIO2_R1")
		)
	)
	(footprint ""
		(layer "B.Cu")
		(at 456.818238 -266.91844 180)
		(property "Reference" "L132"
			(at 0 0 0)
			(layer "B.SilkS")
			(hide yes)
			(effects
				(font
					(size 1.27 1.27)
				)
				(justify mirror)
			)
		)
		(property "Value" ""
			(at 0 0 0)
			(layer "B.Fab")
			(effects
				(font
					(size 1.27 1.27)
				)
				(justify mirror)
			)
		)
		(duplicate_pad_numbers_are_jumpers no)
		(fp_line
			(start 2.248154 4.9911)
			(end -2.248154 4.9911)
			(stroke
				(width 0.1524)
				(type default)
			)
			(layer "B.SilkS")
		)
		(fp_line
			(start 2.248154 1.976882)
			(end 2.248154 4.9911)
			(stroke
				(width 0.1524)
				(type default)
			)
			(layer "B.SilkS")
		)
		(fp_line
			(start 2.248154 -4.9911)
			(end 2.248154 -2.21488)
			(stroke
				(width 0.1524)
				(type default)
			)
			(layer "B.SilkS")
		)
		(fp_line
			(start -2.248154 4.9911)
			(end -2.248154 1.976882)
			(stroke
				(width 0.1524)
				(type default)
			)
			(layer "B.SilkS")
		)
		(fp_line
			(start -2.248154 -2.21488)
			(end -2.248154 -4.9911)
			(stroke
				(width 0.1524)
				(type default)
			)
			(layer "B.SilkS")
		)
		(fp_line
			(start -2.248154 -4.9911)
			(end 2.248154 -4.9911)
			(stroke
				(width 0.1524)
				(type default)
			)
			(layer "B.SilkS")
		)
		(fp_line
			(start 1.700022 0.899922)
			(end -1.700022 0.899922)
			(stroke
				(width 0.1)
				(type default)
			)
			(layer "B.Fab")
		)
		(fp_line
			(start 1.700022 -0.899922)
			(end 1.700022 0.899922)
			(stroke
				(width 0.1)
				(type default)
			)
			(layer "B.Fab")
		)
		(fp_line
			(start -1.700022 0.899922)
			(end -1.700022 -0.899922)
			(stroke
				(width 0.1)
				(type default)
			)
			(layer "B.Fab")
		)
		(fp_line
			(start -1.700022 -0.899922)
			(end 1.700022 -0.899922)
			(stroke
				(width 0.1)
				(type default)
			)
			(layer "B.Fab")
		)
		(pad "1" smd rect
			(at 1.575054 0)
			(size 1.1684 9.8044)
			(layers "B.Cu" "B.Mask" "B.Paste")
			(net "P1V25_PEX3")
		)
		(pad "2" smd rect
			(at -1.575054 0)
			(size 1.1684 9.8044)
			(layers "B.Cu" "B.Mask" "B.Paste")
			(net "P1V25_SERDES_VDDPLL_PEX3")
		)
	)
	(footprint ""
		(layer "B.Cu")
		(at 229.067614 -214.704168 90)
		(property "Reference" "C2008"
			(at 0 0 90)
			(layer "B.SilkS")
			(hide yes)
			(effects
				(font
					(size 1.27 1.27)
				)
				(justify mirror)
			)
		)
		(property "Value" ""
			(at 0 0 90)
			(layer "B.Fab")
			(effects
				(font
					(size 1.27 1.27)
				)
				(justify mirror)
			)
		)
		(duplicate_pad_numbers_are_jumpers no)
		(fp_line
			(start 0.69215 -0.2921)
			(end -0.69215 -0.2921)
			(stroke
				(width 0.1524)
				(type default)
			)
			(layer "B.SilkS")
		)
		(fp_line
			(start -0.69215 -0.2921)
			(end -0.69215 0.2921)
			(stroke
				(width 0.1524)
				(type default)
			)
			(layer "B.SilkS")
		)
		(fp_line
			(start 0.69215 0.2921)
			(end 0.69215 -0.2921)
			(stroke
				(width 0.1524)
				(type default)
			)
			(layer "B.SilkS")
		)
		(fp_line
			(start -0.69215 0.2921)
			(end 0.69215 0.2921)
			(stroke
				(width 0.1524)
				(type default)
			)
			(layer "B.SilkS")
		)
		(fp_line
			(start 0.51435 -0.2794)
			(end -0.51435 -0.2794)
			(stroke
				(width 0.1)
				(type default)
			)
			(layer "B.Fab")
		)
		(fp_line
			(start -0.51435 -0.2794)
			(end -0.51435 0.2794)
			(stroke
				(width 0.1)
				(type default)
			)
			(layer "B.Fab")
		)
		(fp_line
			(start 0.51435 0.2794)
			(end 0.51435 -0.2794)
			(stroke
				(width 0.1)
				(type default)
			)
			(layer "B.Fab")
		)
		(fp_line
			(start -0.51435 0.2794)
			(end 0.51435 0.2794)
			(stroke
				(width 0.1)
				(type default)
			)
			(layer "B.Fab")
		)
		(pad "1" smd circle
			(at 0.40005 0 270)
			(size 0 0)
			(layers "B.Cu" "B.Mask" "B.Paste")
			(net "P3V3_AUX")
		)
		(pad "2" smd circle
			(at -0.40005 0 270)
			(size 0 0)
			(layers "B.Cu" "B.Mask" "B.Paste")
			(net "GND")
		)
		(zone
			(layer "B.Cu")
			(hatch none 0.5)
			(connect_pads
				(clearance 0)
			)
			(min_thickness 0.25)
			(keepout
				(tracks not_allowed)
				(vias allowed)
				(pads allowed)
				(copperpour not_allowed)
				(footprints allowed)
			)
			(placement
				(enabled no)
				(sheetname "")
			)
			(fill
				(thermal_gap 0.5)
				(thermal_bridge_width 0.5)
				(island_removal_mode 0)
			)
			(polygon
				(pts
					(xy 229.155244 -214.894668) (xy 229.21341 -214.803228) (xy 229.21341 -214.603838) (xy 229.155244 -214.513668)
					(xy 228.979984 -214.513668) (xy 228.921564 -214.603838) (xy 228.921564 -214.803228) (xy 228.97973 -214.894668)
				)
			)
		)
	)
	(footprint ""
		(layer "B.Cu")
		(at 123.330208 -282.238958 180)
		(property "Reference" "PR7168"
			(at 0 0 0)
			(layer "B.SilkS")
			(hide yes)
			(effects
				(font
					(size 1.27 1.27)
				)
				(justify mirror)
			)
		)
		(property "Value" ""
			(at 0 0 0)
			(layer "B.Fab")
			(effects
				(font
					(size 1.27 1.27)
				)
				(justify mirror)
			)
		)
		(duplicate_pad_numbers_are_jumpers no)
		(fp_line
			(start 0.7874 0.4064)
			(end 0.7874 -0.4064)
			(stroke
				(width 0.1524)
				(type default)
			)
			(layer "B.SilkS")
		)
		(fp_line
			(start 0.7874 -0.4064)
			(end -0.7874 -0.4064)
			(stroke
				(width 0.1524)
				(type default)
			)
			(layer "B.SilkS")
		)
		(fp_line
			(start -0.7874 0.4064)
			(end 0.7874 0.4064)
			(stroke
				(width 0.1524)
				(type default)
			)
			(layer "B.SilkS")
		)
		(fp_line
			(start -0.7874 -0.4064)
			(end -0.7874 0.4064)
			(stroke
				(width 0.1524)
				(type default)
			)
			(layer "B.SilkS")
		)
		(fp_line
			(start 0.67945 0.3048)
			(end 0.67945 -0.305054)
			(stroke
				(width 0.1)
				(type default)
			)
			(layer "B.Fab")
		)
		(fp_line
			(start 0.67945 -0.305054)
			(end 0.12065 -0.305054)
			(stroke
				(width 0.1)
				(type default)
			)
			(layer "B.Fab")
		)
		(fp_line
			(start 0.12065 0.3048)
			(end 0.67945 0.3048)
			(stroke
				(width 0.1)
				(type default)
			)
			(layer "B.Fab")
		)
		(fp_line
			(start 0.12065 0.2794)
			(end 0.12065 0.3048)
			(stroke
				(width 0.1)
				(type default)
			)
			(layer "B.Fab")
		)
		(fp_line
			(start 0.12065 -0.2794)
			(end -0.12065 -0.2794)
			(stroke
				(width 0.1)
				(type default)
			)
			(layer "B.Fab")
		)
		(fp_line
			(start 0.12065 -0.305054)
			(end 0.12065 -0.2794)
			(stroke
				(width 0.1)
				(type default)
			)
			(layer "B.Fab")
		)
		(fp_line
			(start -0.120396 0.3048)
			(end -0.120396 0.2794)
			(stroke
				(width 0.1)
				(type default)
			)
			(layer "B.Fab")
		)
		(fp_line
			(start -0.120396 0.2794)
			(end 0.12065 0.2794)
			(stroke
				(width 0.1)
				(type default)
			)
			(layer "B.Fab")
		)
		(fp_line
			(start -0.12065 -0.2794)
			(end -0.12065 -0.3048)
			(stroke
				(width 0.1)
				(type default)
			)
			(layer "B.Fab")
		)
		(fp_line
			(start -0.12065 -0.3048)
			(end -0.67945 -0.3048)
			(stroke
				(width 0.1)
				(type default)
			)
			(layer "B.Fab")
		)
		(fp_line
			(start -0.67945 0.3048)
			(end -0.120396 0.3048)
			(stroke
				(width 0.1)
				(type default)
			)
			(layer "B.Fab")
		)
		(fp_line
			(start -0.67945 -0.3048)
			(end -0.67945 0.3048)
			(stroke
				(width 0.1)
				(type default)
			)
			(layer "B.Fab")
		)
		(pad "1" smd circle
			(at 0.40005 0)
			(size 0 0)
			(layers "B.Cu" "B.Mask" "B.Paste")
			(net "P0V8_PEX0_EN3")
		)
		(pad "2" smd circle
			(at -0.40005 0)
			(size 0 0)
			(layers "B.Cu" "B.Mask" "B.Paste")
			(net "P0V8_PEX1_VCC1")
		)
	)
	(footprint ""
		(layer "B.Cu")
		(at 140.282168 -228.346 90)
		(property "Reference" "R3462"
			(at 0 0 90)
			(layer "B.SilkS")
			(hide yes)
			(effects
				(font
					(size 1.27 1.27)
				)
				(justify mirror)
			)
		)
		(property "Value" ""
			(at 0 0 90)
			(layer "B.Fab")
			(effects
				(font
					(size 1.27 1.27)
				)
				(justify mirror)
			)
		)
		(duplicate_pad_numbers_are_jumpers no)
		(fp_line
			(start 0.7874 -0.4064)
			(end -0.7874 -0.4064)
			(stroke
				(width 0.1524)
				(type default)
			)
			(layer "B.SilkS")
		)
		(fp_line
			(start -0.7874 -0.4064)
			(end -0.7874 0.4064)
			(stroke
				(width 0.1524)
				(type default)
			)
			(layer "B.SilkS")
		)
		(fp_line
			(start 0.7874 0.4064)
			(end 0.7874 -0.4064)
			(stroke
				(width 0.1524)
				(type default)
			)
			(layer "B.SilkS")
		)
		(fp_line
			(start -0.7874 0.4064)
			(end 0.7874 0.4064)
			(stroke
				(width 0.1524)
				(type default)
			)
			(layer "B.SilkS")
		)
		(fp_line
			(start 0.67945 -0.305054)
			(end 0.12065 -0.305054)
			(stroke
				(width 0.1)
				(type default)
			)
			(layer "B.Fab")
		)
		(fp_line
			(start 0.12065 -0.305054)
			(end 0.12065 -0.2794)
			(stroke
				(width 0.1)
				(type default)
			)
			(layer "B.Fab")
		)
		(fp_line
			(start -0.12065 -0.3048)
			(end -0.67945 -0.3048)
			(stroke
				(width 0.1)
				(type default)
			)
			(layer "B.Fab")
		)
		(fp_line
			(start -0.67945 -0.3048)
			(end -0.67945 0.3048)
			(stroke
				(width 0.1)
				(type default)
			)
			(layer "B.Fab")
		)
		(fp_line
			(start 0.12065 -0.2794)
			(end -0.12065 -0.2794)
			(stroke
				(width 0.1)
				(type default)
			)
			(layer "B.Fab")
		)
		(fp_line
			(start -0.12065 -0.2794)
			(end -0.12065 -0.3048)
			(stroke
				(width 0.1)
				(type default)
			)
			(layer "B.Fab")
		)
		(fp_line
			(start 0.12065 0.2794)
			(end 0.12065 0.3048)
			(stroke
				(width 0.1)
				(type default)
			)
			(layer "B.Fab")
		)
		(fp_line
			(start -0.120396 0.2794)
			(end 0.12065 0.2794)
			(stroke
				(width 0.1)
				(type default)
			)
			(layer "B.Fab")
		)
		(fp_line
			(start 0.67945 0.3048)
			(end 0.67945 -0.305054)
			(stroke
				(width 0.1)
				(type default)
			)
			(layer "B.Fab")
		)
		(fp_line
			(start 0.12065 0.3048)
			(end 0.67945 0.3048)
			(stroke
				(width 0.1)
				(type default)
			)
			(layer "B.Fab")
		)
		(fp_line
			(start -0.120396 0.3048)
			(end -0.120396 0.2794)
			(stroke
				(width 0.1)
				(type default)
			)
			(layer "B.Fab")
		)
		(fp_line
			(start -0.67945 0.3048)
			(end -0.120396 0.3048)
			(stroke
				(width 0.1)
				(type default)
			)
			(layer "B.Fab")
		)
		(pad "1" smd circle
			(at 0.40005 0 270)
			(size 0 0)
			(layers "B.Cu" "B.Mask" "B.Paste")
			(net "SPI_PEX1_CS_MUX_N")
		)
		(pad "2" smd circle
			(at -0.40005 0 270)
			(size 0 0)
			(layers "B.Cu" "B.Mask" "B.Paste")
			(net "SPI_PEX1_CS_MUX_R_N")
		)
	)
	(footprint ""
		(layer "B.Cu")
		(at 417.450016 -297.32478 180)
		(property "Reference" "C1929"
			(at 0 0 0)
			(layer "B.SilkS")
			(hide yes)
			(effects
				(font
					(size 1.27 1.27)
				)
				(justify mirror)
			)
		)
		(property "Value" ""
			(at 0 0 0)
			(layer "B.Fab")
			(effects
				(font
					(size 1.27 1.27)
				)
				(justify mirror)
			)
		)
		(duplicate_pad_numbers_are_jumpers no)
		(fp_line
			(start 0.299974 0.150114)
			(end 0.299974 -0.150114)
			(stroke
				(width 0.1)
				(type default)
			)
			(layer "B.Fab")
		)
		(fp_line
			(start 0.299974 -0.150114)
			(end -0.299974 -0.150114)
			(stroke
				(width 0.1)
				(type default)
			)
			(layer "B.Fab")
		)
		(fp_line
			(start -0.299974 0.150114)
			(end 0.299974 0.150114)
			(stroke
				(width 0.1)
				(type default)
			)
			(layer "B.Fab")
		)
		(fp_line
			(start -0.299974 -0.150114)
			(end -0.299974 0.150114)
			(stroke
				(width 0.1)
				(type default)
			)
			(layer "B.Fab")
		)
		(pad "1" smd rect
			(at 0.2667 0)
			(size 0.3048 0.381)
			(layers "B.Cu" "B.Mask" "B.Paste")
			(net "P0V8_SERDES_VDDA_PEX3")
		)
		(pad "2" smd rect
			(at -0.2667 0)
			(size 0.3048 0.381)
			(layers "B.Cu" "B.Mask" "B.Paste")
			(net "GND")
		)
	)
	(footprint ""
		(layer "B.Cu")
		(at 46.1264 -139.8016 180)
		(property "Reference" "C854"
			(at 0 0 0)
			(layer "B.SilkS")
			(hide yes)
			(effects
				(font
					(size 1.27 1.27)
				)
				(justify mirror)
			)
		)
		(property "Value" ""
			(at 0 0 0)
			(layer "B.Fab")
			(effects
				(font
					(size 1.27 1.27)
				)
				(justify mirror)
			)
		)
		(duplicate_pad_numbers_are_jumpers no)
		(fp_line
			(start 0.7874 0.4064)
			(end 0.7874 -0.4064)
			(stroke
				(width 0.1524)
				(type default)
			)
			(layer "B.SilkS")
		)
		(fp_line
			(start 0.7874 -0.4064)
			(end -0.7874 -0.4064)
			(stroke
				(width 0.1524)
				(type default)
			)
			(layer "B.SilkS")
		)
		(fp_line
			(start -0.7874 0.4064)
			(end 0.7874 0.4064)
			(stroke
				(width 0.1524)
				(type default)
			)
			(layer "B.SilkS")
		)
		(fp_line
			(start -0.7874 -0.4064)
			(end -0.7874 0.4064)
			(stroke
				(width 0.1524)
				(type default)
			)
			(layer "B.SilkS")
		)
		(fp_line
			(start 0.67945 0.3048)
			(end 0.67945 -0.305054)
			(stroke
				(width 0.1)
				(type default)
			)
			(layer "B.Fab")
		)
		(fp_line
			(start 0.67945 -0.305054)
			(end 0.12065 -0.305054)
			(stroke
				(width 0.1)
				(type default)
			)
			(layer "B.Fab")
		)
		(fp_line
			(start 0.12065 0.3048)
			(end 0.67945 0.3048)
			(stroke
				(width 0.1)
				(type default)
			)
			(layer "B.Fab")
		)
		(fp_line
			(start 0.12065 0.2794)
			(end 0.12065 0.3048)
			(stroke
				(width 0.1)
				(type default)
			)
			(layer "B.Fab")
		)
		(fp_line
			(start 0.12065 -0.2794)
			(end -0.12065 -0.2794)
			(stroke
				(width 0.1)
				(type default)
			)
			(layer "B.Fab")
		)
		(fp_line
			(start 0.12065 -0.305054)
			(end 0.12065 -0.2794)
			(stroke
				(width 0.1)
				(type default)
			)
			(layer "B.Fab")
		)
		(fp_line
			(start -0.120396 0.3048)
			(end -0.120396 0.2794)
			(stroke
				(width 0.1)
				(type default)
			)
			(layer "B.Fab")
		)
		(fp_line
			(start -0.120396 0.2794)
			(end 0.12065 0.2794)
			(stroke
				(width 0.1)
				(type default)
			)
			(layer "B.Fab")
		)
		(fp_line
			(start -0.12065 -0.2794)
			(end -0.12065 -0.3048)
			(stroke
				(width 0.1)
				(type default)
			)
			(layer "B.Fab")
		)
		(fp_line
			(start -0.12065 -0.3048)
			(end -0.67945 -0.3048)
			(stroke
				(width 0.1)
				(type default)
			)
			(layer "B.Fab")
		)
		(fp_line
			(start -0.67945 0.3048)
			(end -0.120396 0.3048)
			(stroke
				(width 0.1)
				(type default)
			)
			(layer "B.Fab")
		)
		(fp_line
			(start -0.67945 -0.3048)
			(end -0.67945 0.3048)
			(stroke
				(width 0.1)
				(type default)
			)
			(layer "B.Fab")
		)
		(pad "1" smd circle
			(at 0.40005 0)
			(size 0 0)
			(layers "B.Cu" "B.Mask" "B.Paste")
			(net "P3V3_NIC0")
		)
		(pad "2" smd circle
			(at -0.40005 0)
			(size 0 0)
			(layers "B.Cu" "B.Mask" "B.Paste")
			(net "GND")
		)
	)
)
